# T6G (Grand Teton) — schematic netlist excerpt (pin names and nets, part order shuffled) for the footprints in the layout excerpt that follows; sources: Cadence DE-HDL packaged netlist, KiCad conversion of 04192023_DAF0TMB3IC0_F0TG_MB_C_brd_V02_OCP.brd

C266  Q_CAP  0.1UF 10V 10% X7S  pkg C0201  page 323 : A = P0V9_CPU1_RT_2D ; B = GND
R1581  Q_RES  49.9 1% CHIP  pkg 0402LF  page 99 : A = I3C_SPD_DDRAF_CPU1_SCL ; B = I3C_SPD_DDRB_CPU1_SCL
C239  Q_CAP  10PF 50V 1% NPO  pkg 0402  page 55 : A = XTAL_CPU1_R_X32K_X2 ; B = GND

(kicad_pcb
	(version 20260206)
	(generator "pcbnew")
	(generator_version "10.0")
	(general
		(thickness 1.6)
		(legacy_teardrops no)
	)
	(paper "A4")
	(title_block
		(title "04192023_DAF0TMB3IC0_F0TG_MB_C_brd_V02_OCP.brd")
		(comment 1 "Grand Teton / footprints 6066-6068 of 8354")
	)
	(layers
		(0 "F.Cu" signal "TOP")
		(4 "In1.Cu" signal "GND")
		(6 "In2.Cu" signal "IN1")
		(8 "In3.Cu" signal "GND1")
		(10 "In4.Cu" signal "IN2")
		(12 "In5.Cu" signal "GND2")
		(14 "In6.Cu" signal "IN3")
		(16 "In7.Cu" signal "GND3")
		(18 "In8.Cu" signal "VCC")
		(20 "In9.Cu" signal "VCC1")
		(22 "In10.Cu" signal "GND4")
		(24 "In11.Cu" signal "IN4")
		(26 "In12.Cu" signal "GND5")
		(28 "In13.Cu" signal "IN5")
		(30 "In14.Cu" signal "GND6")
		(32 "In15.Cu" signal "IN6")
		(34 "In16.Cu" signal "GND7")
		(2 "B.Cu" signal "BOTTOM")
		(9 "F.Adhes" user "F.Adhesive")
		(11 "B.Adhes" user "B.Adhesive")
		(13 "F.Paste" user "Package Geometry/Pastemask Top")
		(15 "B.Paste" user "Package Geometry/Pastemask Bottom")
		(5 "F.SilkS" user "Ref Des/Silkscreen Top")
		(7 "B.SilkS" user "Ref Des/Silkscreen Bottom")
		(1 "F.Mask" user "Board Geometry/Soldermask Top")
		(3 "B.Mask" user "Board Geometry/Soldermask Bottom")
		(17 "Dwgs.User" user "User.Drawings")
		(19 "Cmts.User" user "User.Comments")
		(21 "Eco1.User" user "User.Eco1")
		(23 "Eco2.User" user "User.Eco2")
		(25 "Edge.Cuts" user "Board Geometry/Outline")
		(27 "Margin" user)
		(31 "F.CrtYd" user "Package Geometry/Place Bound Top")
		(29 "B.CrtYd" user "Package Geometry/Place Bound Bottom")
		(35 "F.Fab" user "Ref Des/Assembly Top")
		(33 "B.Fab" user "Ref Des/Assembly Bottom")
	)
	(footprint ""
		(layer "B.Cu")
		(at 155.491434 -316.049152 90)
		(property "Reference" "C239"
			(at 0 0 90)
			(layer "B.SilkS")
			(hide yes)
			(effects
				(font
					(size 1.27 1.27)
				)
				(justify mirror)
			)
		)
		(property "Value" ""
			(at 0 0 90)
			(layer "B.Fab")
			(effects
				(font
					(size 1.27 1.27)
				)
				(justify mirror)
			)
		)
		(duplicate_pad_numbers_are_jumpers no)
		(fp_line
			(start 0.7874 -0.4064)
			(end -0.7874 -0.4064)
			(stroke
				(width 0.1524)
				(type default)
			)
			(layer "B.SilkS")
		)
		(fp_line
			(start -0.7874 -0.4064)
			(end -0.7874 0.4064)
			(stroke
				(width 0.1524)
				(type default)
			)
			(layer "B.SilkS")
		)
		(fp_line
			(start 0.7874 0.4064)
			(end 0.7874 -0.4064)
			(stroke
				(width 0.1524)
				(type default)
			)
			(layer "B.SilkS")
		)
		(fp_line
			(start -0.7874 0.4064)
			(end 0.7874 0.4064)
			(stroke
				(width 0.1524)
				(type default)
			)
			(layer "B.SilkS")
		)
		(fp_line
			(start 0.67945 -0.305054)
			(end 0.12065 -0.305054)
			(stroke
				(width 0.1)
				(type default)
			)
			(layer "B.Fab")
		)
		(fp_line
			(start 0.12065 -0.305054)
			(end 0.12065 -0.2794)
			(stroke
				(width 0.1)
				(type default)
			)
			(layer "B.Fab")
		)
		(fp_line
			(start -0.12065 -0.3048)
			(end -0.67945 -0.3048)
			(stroke
				(width 0.1)
				(type default)
			)
			(layer "B.Fab")
		)
		(fp_line
			(start -0.67945 -0.3048)
			(end -0.67945 0.3048)
			(stroke
				(width 0.1)
				(type default)
			)
			(layer "B.Fab")
		)
		(fp_line
			(start 0.12065 -0.2794)
			(end -0.12065 -0.2794)
			(stroke
				(width 0.1)
				(type default)
			)
			(layer "B.Fab")
		)
		(fp_line
			(start -0.12065 -0.2794)
			(end -0.12065 -0.3048)
			(stroke
				(width 0.1)
				(type default)
			)
			(layer "B.Fab")
		)
		(fp_line
			(start 0.12065 0.2794)
			(end 0.12065 0.3048)
			(stroke
				(width 0.1)
				(type default)
			)
			(layer "B.Fab")
		)
		(fp_line
			(start -0.120396 0.2794)
			(end 0.12065 0.2794)
			(stroke
				(width 0.1)
				(type default)
			)
			(layer "B.Fab")
		)
		(fp_line
			(start 0.67945 0.3048)
			(end 0.67945 -0.305054)
			(stroke
				(width 0.1)
				(type default)
			)
			(layer "B.Fab")
		)
		(fp_line
			(start 0.12065 0.3048)
			(end 0.67945 0.3048)
			(stroke
				(width 0.1)
				(type default)
			)
			(layer "B.Fab")
		)
		(fp_line
			(start -0.120396 0.3048)
			(end -0.120396 0.2794)
			(stroke
				(width 0.1)
				(type default)
			)
			(layer "B.Fab")
		)
		(fp_line
			(start -0.67945 0.3048)
			(end -0.120396 0.3048)
			(stroke
				(width 0.1)
				(type default)
			)
			(layer "B.Fab")
		)
		(pad "1" smd circle
			(at 0.40005 0 270)
			(size 0 0)
			(layers "B.Cu" "B.Mask" "B.Paste")
			(net "XTAL_CPU1_R_X32K_X2")
		)
		(pad "2" smd circle
			(at -0.40005 0 270)
			(size 0 0)
			(layers "B.Cu" "B.Mask" "B.Paste")
			(net "GND")
		)
	)
	(footprint ""
		(layer "B.Cu")
		(at 59.378596 -386.766562 90)
		(property "Reference" "C266"
			(at 0 0 90)
			(layer "B.SilkS")
			(hide yes)
			(effects
				(font
					(size 1.27 1.27)
				)
				(justify mirror)
			)
		)
		(property "Value" ""
			(at 0 0 90)
			(layer "B.Fab")
			(effects
				(font
					(size 1.27 1.27)
				)
				(justify mirror)
			)
		)
		(duplicate_pad_numbers_are_jumpers no)
		(fp_line
			(start 0.299974 -0.150114)
			(end -0.299974 -0.150114)
			(stroke
				(width 0.1)
				(type default)
			)
			(layer "B.Fab")
		)
		(fp_line
			(start -0.299974 -0.150114)
			(end -0.299974 0.150114)
			(stroke
				(width 0.1)
				(type default)
			)
			(layer "B.Fab")
		)
		(fp_line
			(start 0.299974 0.150114)
			(end 0.299974 -0.150114)
			(stroke
				(width 0.1)
				(type default)
			)
			(layer "B.Fab")
		)
		(fp_line
			(start -0.299974 0.150114)
			(end 0.299974 0.150114)
			(stroke
				(width 0.1)
				(type default)
			)
			(layer "B.Fab")
		)
		(pad "1" smd rect
			(at 0.2667 0 270)
			(size 0.3048 0.381)
			(layers "B.Cu" "B.Mask" "B.Paste")
			(net "P0V9_CPU1_RT_2D")
		)
		(pad "2" smd rect
			(at -0.2667 0 270)
			(size 0.3048 0.381)
			(layers "B.Cu" "B.Mask" "B.Paste")
			(net "GND")
		)
	)
	(footprint ""
		(layer "B.Cu")
		(at 51.128422 -194.9196 180)
		(property "Reference" "R1581"
			(at 0 0 0)
			(layer "B.SilkS")
			(hide yes)
			(effects
				(font
					(size 1.27 1.27)
				)
				(justify mirror)
			)
		)
		(property "Value" ""
			(at 0 0 0)
			(layer "B.Fab")
			(effects
				(font
					(size 1.27 1.27)
				)
				(justify mirror)
			)
		)
		(duplicate_pad_numbers_are_jumpers no)
		(fp_line
			(start 0.7874 0.4064)
			(end 0.7874 -0.4064)
			(stroke
				(width 0.1524)
				(type default)
			)
			(layer "B.SilkS")
		)
		(fp_line
			(start 0.7874 -0.4064)
			(end -0.7874 -0.4064)
			(stroke
				(width 0.1524)
				(type default)
			)
			(layer "B.SilkS")
		)
		(fp_line
			(start -0.7874 0.4064)
			(end 0.7874 0.4064)
			(stroke
				(width 0.1524)
				(type default)
			)
			(layer "B.SilkS")
		)
		(fp_line
			(start -0.7874 -0.4064)
			(end -0.7874 0.4064)
			(stroke
				(width 0.1524)
				(type default)
			)
			(layer "B.SilkS")
		)
		(fp_line
			(start 0.67945 0.3048)
			(end 0.67945 -0.305054)
			(stroke
				(width 0.1)
				(type default)
			)
			(layer "B.Fab")
		)
		(fp_line
			(start 0.67945 -0.305054)
			(end 0.12065 -0.305054)
			(stroke
				(width 0.1)
				(type default)
			)
			(layer "B.Fab")
		)
		(fp_line
			(start 0.12065 0.3048)
			(end 0.67945 0.3048)
			(stroke
				(width 0.1)
				(type default)
			)
			(layer "B.Fab")
		)
		(fp_line
			(start 0.12065 0.2794)
			(end 0.12065 0.3048)
			(stroke
				(width 0.1)
				(type default)
			)
			(layer "B.Fab")
		)
		(fp_line
			(start 0.12065 -0.2794)
			(end -0.12065 -0.2794)
			(stroke
				(width 0.1)
				(type default)
			)
			(layer "B.Fab")
		)
		(fp_line
			(start 0.12065 -0.305054)
			(end 0.12065 -0.2794)
			(stroke
				(width 0.1)
				(type default)
			)
			(layer "B.Fab")
		)
		(fp_line
			(start -0.120396 0.3048)
			(end -0.120396 0.2794)
			(stroke
				(width 0.1)
				(type default)
			)
			(layer "B.Fab")
		)
		(fp_line
			(start -0.120396 0.2794)
			(end 0.12065 0.2794)
			(stroke
				(width 0.1)
				(type default)
			)
			(layer "B.Fab")
		)
		(fp_line
			(start -0.12065 -0.2794)
			(end -0.12065 -0.3048)
			(stroke
				(width 0.1)
				(type default)
			)
			(layer "B.Fab")
		)
		(fp_line
			(start -0.12065 -0.3048)
			(end -0.67945 -0.3048)
			(stroke
				(width 0.1)
				(type default)
			)
			(layer "B.Fab")
		)
		(fp_line
			(start -0.67945 0.3048)
			(end -0.120396 0.3048)
			(stroke
				(width 0.1)
				(type default)
			)
			(layer "B.Fab")
		)
		(fp_line
			(start -0.67945 -0.3048)
			(end -0.67945 0.3048)
			(stroke
				(width 0.1)
				(type default)
			)
			(layer "B.Fab")
		)
		(pad "1" smd circle
			(at 0.40005 0)
			(size 0 0)
			(layers "B.Cu" "B.Mask" "B.Paste")
			(net "I3C_SPD_DDRAF_CPU1_SCL")
		)
		(pad "2" smd circle
			(at -0.40005 0)
			(size 0 0)
			(layers "B.Cu" "B.Mask" "B.Paste")
			(net "I3C_SPD_DDRB_CPU1_SCL")
		)
	)
)
